(kicad_pcb
	(version 20260206)
	(generator "pcbnew")
	(generator_version "10.0")
	(general
		(thickness 1.6)
		(legacy_teardrops no)
	)
	(paper "A4")
	(title_block
		(title "Wiwynn_Tioga_Pass_MB.brd")
		(comment 1 "Tioga Pass / footprint 241 of 4770 (EU1C2), pads 43-49 of 49")
	)
	(layers
		(0 "F.Cu" signal "TOP")
		(4 "In1.Cu" signal "L2GND")
		(6 "In2.Cu" signal "L3")
		(8 "In3.Cu" signal "L4GND")
		(10 "In4.Cu" signal "L5")
		(12 "In5.Cu" signal "L6GND")
		(14 "In6.Cu" signal "L7VCC")
		(16 "In7.Cu" signal "L8VCC")
		(18 "In8.Cu" signal "L9GND")
		(20 "In9.Cu" signal "L10")
		(22 "In10.Cu" signal "L11GND")
		(24 "In11.Cu" signal "L12")
		(26 "In12.Cu" signal "L13GND")
		(2 "B.Cu" signal "BOTTOM")
		(9 "F.Adhes" user "F.Adhesive")
		(11 "B.Adhes" user "B.Adhesive")
		(13 "F.Paste" user "Package Geometry/Pastemask Top")
		(15 "B.Paste" user "Package Geometry/Pastemask Bottom")
		(5 "F.SilkS" user "Ref Des/Silkscreen Top")
		(7 "B.SilkS" user "Ref Des/Silkscreen Bottom")
		(1 "F.Mask" user "Board Geometry/Soldermask Top")
		(3 "B.Mask" user "Board Geometry/Soldermask Bottom")
		(17 "Dwgs.User" user "User.Drawings")
		(19 "Cmts.User" user "User.Comments")
		(21 "Eco1.User" user "User.Eco1")
		(23 "Eco2.User" user "User.Eco2")
		(25 "Edge.Cuts" user "Board Geometry/Outline")
		(27 "Margin" user)
		(31 "F.CrtYd" user "Package Geometry/Place Bound Top")
		(29 "B.CrtYd" user "Package Geometry/Place Bound Bottom")
		(35 "F.Fab" user "Ref Des/Assembly Top")
		(33 "B.Fab" user "Ref Des/Assembly Bottom")
	)
	(footprint ""
		(layer "F.Cu")
		(at 19.431 -92.456)
		(property "Reference" "EU1C2"
			(at -7.8232 -3.45313 0)
			(unlocked yes)
			(layer "F.SilkS")
			(effects
				(font
					(size 0.7874 0.5842)
					(thickness 0.1524)
				)
				(justify left)
			)
		)
		(property "Value" ""
			(at 0 0 0)
			(layer "F.Fab")
			(effects
				(font
					(size 1.27 1.27)
				)
			)
		)
		(duplicate_pad_numbers_are_jumpers no)
		(pad "43" smd custom
			(at -0.199898 -2.8956)
			(size 0.0508 0.0508)
			(layers "F.Cu" "F.Mask" "F.Paste")
			(net "A_TSENSE_PVCCIN_CPU1")
			(options
				(clearance outline)
				(anchor circle)
			)
			(primitives
				(gr_poly
					(pts
						(arc
							(start 0.1016 0.254)
							(mid 0 0.3556)
							(end -0.1016 0.254)
						)
						(xy -0.1016 -0.3556) (xy 0.1016 -0.3556)
					)
					(width 0)
					(fill yes)
				)
			)
		)
		(pad "44" smd custom
			(at -0.599948 -2.8956)
			(size 0.0508 0.0508)
			(layers "F.Cu" "F.Mask" "F.Paste")
			(net "VR_PVCCIN_CPU1_XADDR1")
			(options
				(clearance outline)
				(anchor circle)
			)
			(primitives
				(gr_poly
					(pts
						(arc
							(start 0.1016 0.254)
							(mid 0 0.3556)
							(end -0.1016 0.254)
						)
						(xy -0.1016 -0.3556) (xy 0.1016 -0.3556)
					)
					(width 0)
					(fill yes)
				)
			)
		)
		(pad "45" smd custom
			(at -0.999998 -2.8956)
			(size 0.0508 0.0508)
			(layers "F.Cu" "F.Mask" "F.Paste")
			(net "VR_PVCCIN_CPU1_AVINSEN")
			(options
				(clearance outline)
				(anchor circle)
			)
			(primitives
				(gr_poly
					(pts
						(arc
							(start 0.1016 0.254)
							(mid 0 0.3556)
							(end -0.1016 0.254)
						)
						(xy -0.1016 -0.3556) (xy 0.1016 -0.3556)
					)
					(width 0)
					(fill yes)
				)
			)
		)
		(pad "46" smd custom
			(at -1.400048 -2.8956)
			(size 0.0508 0.0508)
			(layers "F.Cu" "F.Mask" "F.Paste")
			(net "Net_218")
			(options
				(clearance outline)
				(anchor circle)
			)
			(primitives
				(gr_poly
					(pts
						(arc
							(start 0.1016 0.254)
							(mid 0 0.3556)
							(end -0.1016 0.254)
						)
						(xy -0.1016 -0.3556) (xy 0.1016 -0.3556)
					)
					(width 0)
					(fill yes)
				)
			)
		)
		(pad "47" smd custom
			(at -1.800098 -2.8956)
			(size 0.0508 0.0508)
			(layers "F.Cu" "F.Mask" "F.Paste")
			(net "VR_PVCCIN_CPU1_VDD")
			(options
				(clearance outline)
				(anchor circle)
			)
			(primitives
				(gr_poly
					(pts
						(arc
							(start 0.1016 0.254)
							(mid 0 0.3556)
							(end -0.1016 0.254)
						)
						(xy -0.1016 -0.3556) (xy 0.1016 -0.3556)
					)
					(width 0)
					(fill yes)
				)
			)
		)
		(pad "48" smd custom
			(at -2.199894 -2.8956)
			(size 0.0508 0.0508)
			(layers "F.Cu" "F.Mask" "F.Paste")
			(net "VR_PVCCIN_CPU1_VD12")
			(options
				(clearance outline)
				(anchor circle)
			)
			(primitives
				(gr_poly
					(pts
						(arc
							(start 0.1016 0.254)
							(mid 0 0.3556)
							(end -0.1016 0.254)
						)
						(xy -0.1016 -0.3556) (xy 0.1016 -0.3556)
					)
					(width 0)
					(fill yes)
				)
			)
		)
		(pad "49" smd rect
			(at 0 0)
			(size 3.6068 3.6068)
			(layers "F.Cu" "F.Mask" "F.Paste")
			(net "GND")
		)
	)
)
